# S9S_MB_2U (Grand Teton) — schematic netlist excerpt (pin names and nets, part order shuffled) for the footprints in the layout excerpt that follows; sources: Cadence DE-HDL packaged netlist, KiCad conversion of 03242023_DA0F0TMBIJ0_F0T_Motherboard_J_brd_V01_OCP.brd

PC2085  Q_CAP  1UF 25V 10% EMPTY  pkg C0402  page 156 : A = P12V_OCP_VCC_1 ; B = GND

U301  GTL2014PW  IC  pkg TSSOP14  page 226
  DIR  = PD_CPU0_ERRS_DIR
  B0  = H_CPU_CATERR_LVC1_R_N
  B1  = H_CPU_CATERR_LVC1_R_N
  VREF  = P0V62_CPU0_ERRS_VREF
  B2  = H_CPU_RMCA_LVC1_R_N
  B3  = PWRGD_CPUPWRGD_LVC1
  GND_0  = GND
  GND_1  = GND
  A3  = PWRGD_CPUPWRGD_LVC2_R
  A2  = H_CPU_RMCA_LVC2_R1_N
  GND_2  = GND
  A1  = H_CPU_CATERR_LVC2_R1_N
  A0  = H_CPU_CATERR_LVC2_BMC_R_N
  VCC  = P3V3

(kicad_pcb
	(version 20260206)
	(generator "pcbnew")
	(generator_version "10.0")
	(general
		(thickness 1.6)
		(legacy_teardrops no)
	)
	(paper "A4")
	(title_block
		(title "03242023_DA0F0TMBIJ0_F0T_Motherboard_J_brd_V01_OCP.brd")
		(comment 1 "Grand Teton / footprints 1672-1673 of 6105")
	)
	(layers
		(0 "F.Cu" signal "TOP")
		(4 "In1.Cu" signal "GND")
		(6 "In2.Cu" signal "IN1")
		(8 "In3.Cu" signal "GND1")
		(10 "In4.Cu" signal "IN2")
		(12 "In5.Cu" signal "GND2")
		(14 "In6.Cu" signal "IN3")
		(16 "In7.Cu" signal "GND3")
		(18 "In8.Cu" signal "VCC")
		(20 "In9.Cu" signal "VCC1")
		(22 "In10.Cu" signal "GND4")
		(24 "In11.Cu" signal "IN4")
		(26 "In12.Cu" signal "GND5")
		(28 "In13.Cu" signal "IN5")
		(30 "In14.Cu" signal "GND6")
		(32 "In15.Cu" signal "IN6")
		(34 "In16.Cu" signal "GND7")
		(2 "B.Cu" signal "BOTTOM")
		(9 "F.Adhes" user "F.Adhesive")
		(11 "B.Adhes" user "B.Adhesive")
		(13 "F.Paste" user "Package Geometry/Pastemask Top")
		(15 "B.Paste" user "Package Geometry/Pastemask Bottom")
		(5 "F.SilkS" user "Ref Des/Silkscreen Top")
		(7 "B.SilkS" user "Ref Des/Silkscreen Bottom")
		(1 "F.Mask" user "Board Geometry/Soldermask Top")
		(3 "B.Mask" user "Board Geometry/Soldermask Bottom")
		(17 "Dwgs.User" user "User.Drawings")
		(19 "Cmts.User" user "User.Comments")
		(21 "Eco1.User" user "User.Eco1")
		(23 "Eco2.User" user "User.Eco2")
		(25 "Edge.Cuts" user "Board Geometry/Outline")
		(27 "Margin" user)
		(31 "F.CrtYd" user "Package Geometry/Place Bound Top")
		(29 "B.CrtYd" user "Package Geometry/Place Bound Bottom")
		(35 "F.Fab" user "Ref Des/Assembly Top")
		(33 "B.Fab" user "Ref Des/Assembly Bottom")
	)
	(footprint ""
		(layer "F.Cu")
		(at 115.219734 -95.504762 -90)
		(property "Reference" "U301"
			(at -0.353568 -3.017266 0)
			(unlocked yes)
			(layer "F.SilkS")
			(effects
				(font
					(size 0.7874 0.5842)
					(thickness 0.1524)
				)
				(justify left)
			)
		)
		(property "Value" ""
			(at 0 0 270)
			(layer "F.Fab")
			(effects
				(font
					(size 1.27 1.27)
				)
			)
		)
		(duplicate_pad_numbers_are_jumpers no)
		(fp_line
			(start -2.0066 2.5527)
			(end -2.0066 -2.5527)
			(stroke
				(width 0.1524)
				(type default)
			)
			(layer "F.SilkS")
		)
		(fp_line
			(start 2.0066 2.5527)
			(end -2.0066 2.5527)
			(stroke
				(width 0.1524)
				(type default)
			)
			(layer "F.SilkS")
		)
		(fp_line
			(start 0 -1.9812)
			(end 0.5715 -2.5527)
			(stroke
				(width 0.1524)
				(type default)
			)
			(layer "F.SilkS")
		)
		(fp_line
			(start -2.0066 -2.5527)
			(end -0.5715 -2.5527)
			(stroke
				(width 0.1524)
				(type default)
			)
			(layer "F.SilkS")
		)
		(fp_line
			(start -0.5715 -2.5527)
			(end 0 -1.9812)
			(stroke
				(width 0.1524)
				(type default)
			)
			(layer "F.SilkS")
		)
		(fp_line
			(start 0.5715 -2.5527)
			(end 2.0066 -2.5527)
			(stroke
				(width 0.1524)
				(type default)
			)
			(layer "F.SilkS")
		)
		(fp_line
			(start 2.0066 -2.5527)
			(end 2.0066 2.5527)
			(stroke
				(width 0.1524)
				(type default)
			)
			(layer "F.SilkS")
		)
		(fp_poly
			(pts
				(xy -2.958084 -2.921) (xy -3.286252 -2.36728) (xy -3.582924 -2.921)
			)
			(stroke
				(width 0)
				(type default)
			)
			(fill yes)
			(layer "F.SilkS")
		)
		(fp_line
			(start -2.249932 2.549906)
			(end -2.249932 -2.549906)
			(stroke
				(width 0.1)
				(type default)
			)
			(layer "F.Fab")
		)
		(fp_line
			(start 2.249932 2.549906)
			(end -2.249932 2.549906)
			(stroke
				(width 0.1)
				(type default)
			)
			(layer "F.Fab")
		)
		(fp_line
			(start -2.249932 -2.549906)
			(end 2.249932 -2.549906)
			(stroke
				(width 0.1)
				(type default)
			)
			(layer "F.Fab")
		)
		(fp_line
			(start 2.249932 -2.549906)
			(end 2.249932 2.549906)
			(stroke
				(width 0.1)
				(type default)
			)
			(layer "F.Fab")
		)
		(fp_poly
			(pts
				(xy -4.36372 -1.608328) (xy -4.36372 -2.233168) (xy -3.81 -1.905)
			)
			(stroke
				(width 0)
				(type default)
			)
			(fill yes)
			(layer "F.Fab")
		)
		(pad "1" smd rect
			(at -2.921 -1.949958 180)
			(size 0.3556 1.4986)
			(layers "F.Cu" "F.Mask" "F.Paste")
			(net "PD_CPU0_ERRS_DIR")
		)
		(pad "2" smd rect
			(at -2.921 -1.299972 180)
			(size 0.3556 1.4986)
			(layers "F.Cu" "F.Mask" "F.Paste")
			(net "H_CPU_CATERR_LVC1_R_N")
		)
		(pad "3" smd rect
			(at -2.921 -0.649986 180)
			(size 0.3556 1.4986)
			(layers "F.Cu" "F.Mask" "F.Paste")
			(net "H_CPU_CATERR_LVC1_R_N")
		)
		(pad "4" smd rect
			(at -2.921 0 180)
			(size 0.3556 1.4986)
			(layers "F.Cu" "F.Mask" "F.Paste")
			(net "P0V62_CPU0_ERRS_VREF")
		)
		(pad "5" smd rect
			(at -2.921 0.649986 180)
			(size 0.3556 1.4986)
			(layers "F.Cu" "F.Mask" "F.Paste")
			(net "H_CPU_RMCA_LVC1_R_N")
		)
		(pad "6" smd rect
			(at -2.921 1.299972 180)
			(size 0.3556 1.4986)
			(layers "F.Cu" "F.Mask" "F.Paste")
			(net "PWRGD_CPUPWRGD_LVC1")
		)
		(pad "7" smd rect
			(at -2.921 1.949958 180)
			(size 0.3556 1.4986)
			(layers "F.Cu" "F.Mask" "F.Paste")
			(net "GND")
		)
		(pad "8" smd rect
			(at 2.921 1.949958 180)
			(size 0.3556 1.4986)
			(layers "F.Cu" "F.Mask" "F.Paste")
			(net "GND")
		)
		(pad "9" smd rect
			(at 2.921 1.299972 180)
			(size 0.3556 1.4986)
			(layers "F.Cu" "F.Mask" "F.Paste")
			(net "PWRGD_CPUPWRGD_LVC2_R")
		)
		(pad "10" smd rect
			(at 2.921 0.649986 180)
			(size 0.3556 1.4986)
			(layers "F.Cu" "F.Mask" "F.Paste")
			(net "H_CPU_RMCA_LVC2_R1_N")
		)
		(pad "11" smd rect
			(at 2.921 0 180)
			(size 0.3556 1.4986)
			(layers "F.Cu" "F.Mask" "F.Paste")
			(net "GND")
		)
		(pad "12" smd rect
			(at 2.921 -0.649986 180)
			(size 0.3556 1.4986)
			(layers "F.Cu" "F.Mask" "F.Paste")
			(net "H_CPU_CATERR_LVC2_R1_N")
		)
		(pad "13" smd rect
			(at 2.921 -1.299972 180)
			(size 0.3556 1.4986)
			(layers "F.Cu" "F.Mask" "F.Paste")
			(net "H_CPU_CATERR_LVC2_BMC_R_N")
		)
		(pad "14" smd rect
			(at 2.921 -1.949958 180)
			(size 0.3556 1.4986)
			(layers "F.Cu" "F.Mask" "F.Paste")
			(net "P3V3")
		)
	)
	(footprint ""
		(layer "F.Cu")
		(at 449.650612 -23.594314 180)
		(property "Reference" "PC2085"
			(at 0 0 180)
			(layer "F.SilkS")
			(hide yes)
			(effects
				(font
					(size 1.27 1.27)
				)
			)
		)
		(property "Value" ""
			(at 0 0 180)
			(layer "F.Fab")
			(effects
				(font
					(size 1.27 1.27)
				)
			)
		)
		(duplicate_pad_numbers_are_jumpers no)
		(fp_line
			(start 0.7874 0.4064)
			(end -0.7874 0.4064)
			(stroke
				(width 0.1524)
				(type default)
			)
			(layer "F.SilkS")
		)
		(fp_line
			(start 0.7874 -0.4064)
			(end 0.7874 0.4064)
			(stroke
				(width 0.1524)
				(type default)
			)
			(layer "F.SilkS")
		)
		(fp_line
			(start -0.7874 0.4064)
			(end -0.7874 -0.4064)
			(stroke
				(width 0.1524)
				(type default)
			)
			(layer "F.SilkS")
		)
		(fp_line
			(start -0.7874 -0.4064)
			(end 0.7874 -0.4064)
			(stroke
				(width 0.1524)
				(type default)
			)
			(layer "F.SilkS")
		)
		(fp_line
			(start 0.67945 0.3048)
			(end 0.120396 0.3048)
			(stroke
				(width 0.1)
				(type default)
			)
			(layer "F.Fab")
		)
		(fp_line
			(start 0.67945 -0.3048)
			(end 0.67945 0.3048)
			(stroke
				(width 0.1)
				(type default)
			)
			(layer "F.Fab")
		)
		(fp_line
			(start 0.12065 -0.2794)
			(end 0.12065 -0.3048)
			(stroke
				(width 0.1)
				(type default)
			)
			(layer "F.Fab")
		)
		(fp_line
			(start 0.12065 -0.3048)
			(end 0.67945 -0.3048)
			(stroke
				(width 0.1)
				(type default)
			)
			(layer "F.Fab")
		)
		(fp_line
			(start 0.120396 0.3048)
			(end 0.120396 0.2794)
			(stroke
				(width 0.1)
				(type default)
			)
			(layer "F.Fab")
		)
		(fp_line
			(start 0.120396 0.2794)
			(end -0.12065 0.2794)
			(stroke
				(width 0.1)
				(type default)
			)
			(layer "F.Fab")
		)
		(fp_line
			(start -0.12065 0.3048)
			(end -0.67945 0.3048)
			(stroke
				(width 0.1)
				(type default)
			)
			(layer "F.Fab")
		)
		(fp_line
			(start -0.12065 0.2794)
			(end -0.12065 0.3048)
			(stroke
				(width 0.1)
				(type default)
			)
			(layer "F.Fab")
		)
		(fp_line
			(start -0.12065 -0.2794)
			(end 0.12065 -0.2794)
			(stroke
				(width 0.1)
				(type default)
			)
			(layer "F.Fab")
		)
		(fp_line
			(start -0.12065 -0.305054)
			(end -0.12065 -0.2794)
			(stroke
				(width 0.1)
				(type default)
			)
			(layer "F.Fab")
		)
		(fp_line
			(start -0.67945 0.3048)
			(end -0.67945 -0.305054)
			(stroke
				(width 0.1)
				(type default)
			)
			(layer "F.Fab")
		)
		(fp_line
			(start -0.67945 -0.305054)
			(end -0.12065 -0.305054)
			(stroke
				(width 0.1)
				(type default)
			)
			(layer "F.Fab")
		)
		(pad "1" smd circle
			(at -0.40005 0 180)
			(size 0 0)
			(layers "F.Cu" "F.Mask" "F.Paste")
			(net "P12V_OCP_VCC_1")
		)
		(pad "2" smd circle
			(at 0.40005 0 180)
			(size 0 0)
			(layers "F.Cu" "F.Mask" "F.Paste")
			(net "GND")
		)
	)
)
